# S9S_MB_2U (Grand Teton) — schematic netlist excerpt (pin names and nets, part order shuffled) for the footprints in the layout excerpt that follows; sources: Cadence DE-HDL packaged netlist, KiCad conversion of 03242023_DA0F0TMBIJ0_F0T_Motherboard_J_brd_V01_OCP.brd

PR2522  Q_RES  1 1% EMPTY  pkg 0402LF  page 304 : A = P12V_HSC_SENSE2_P ; B = P12V_HSC_SENSE2_R3_P
R2551  Q_RES  1K 1% CHIP  pkg 0402LF  page 284 : A = P3V3_AUX ; B = PWRGD_PVCCFA_EHV_FIVRA_CPU1_R

(kicad_pcb
	(version 20260206)
	(generator "pcbnew")
	(generator_version "10.0")
	(general
		(thickness 1.6)
		(legacy_teardrops no)
	)
	(paper "A4")
	(title_block
		(title "03242023_DA0F0TMBIJ0_F0T_Motherboard_J_brd_V01_OCP.brd")
		(comment 1 "Grand Teton / footprints 5115-5116 of 6105")
	)
	(layers
		(0 "F.Cu" signal "TOP")
		(4 "In1.Cu" signal "GND")
		(6 "In2.Cu" signal "IN1")
		(8 "In3.Cu" signal "GND1")
		(10 "In4.Cu" signal "IN2")
		(12 "In5.Cu" signal "GND2")
		(14 "In6.Cu" signal "IN3")
		(16 "In7.Cu" signal "GND3")
		(18 "In8.Cu" signal "VCC")
		(20 "In9.Cu" signal "VCC1")
		(22 "In10.Cu" signal "GND4")
		(24 "In11.Cu" signal "IN4")
		(26 "In12.Cu" signal "GND5")
		(28 "In13.Cu" signal "IN5")
		(30 "In14.Cu" signal "GND6")
		(32 "In15.Cu" signal "IN6")
		(34 "In16.Cu" signal "GND7")
		(2 "B.Cu" signal "BOTTOM")
		(9 "F.Adhes" user "F.Adhesive")
		(11 "B.Adhes" user "B.Adhesive")
		(13 "F.Paste" user "Package Geometry/Pastemask Top")
		(15 "B.Paste" user "Package Geometry/Pastemask Bottom")
		(5 "F.SilkS" user "Ref Des/Silkscreen Top")
		(7 "B.SilkS" user "Ref Des/Silkscreen Bottom")
		(1 "F.Mask" user "Board Geometry/Soldermask Top")
		(3 "B.Mask" user "Board Geometry/Soldermask Bottom")
		(17 "Dwgs.User" user "User.Drawings")
		(19 "Cmts.User" user "User.Comments")
		(21 "Eco1.User" user "User.Eco1")
		(23 "Eco2.User" user "User.Eco2")
		(25 "Edge.Cuts" user "Board Geometry/Outline")
		(27 "Margin" user)
		(31 "F.CrtYd" user "Package Geometry/Place Bound Top")
		(29 "B.CrtYd" user "Package Geometry/Place Bound Bottom")
		(35 "F.Fab" user "Ref Des/Assembly Top")
		(33 "B.Fab" user "Ref Des/Assembly Bottom")
	)
	(footprint ""
		(layer "B.Cu")
		(at 295.93413 -400.999452 -90)
		(property "Reference" "PR2522"
			(at 0 0 90)
			(layer "B.SilkS")
			(hide yes)
			(effects
				(font
					(size 1.27 1.27)
				)
				(justify mirror)
			)
		)
		(property "Value" ""
			(at 0 0 90)
			(layer "B.Fab")
			(effects
				(font
					(size 1.27 1.27)
				)
				(justify mirror)
			)
		)
		(duplicate_pad_numbers_are_jumpers no)
		(fp_line
			(start -0.7874 0.4064)
			(end 0.7874 0.4064)
			(stroke
				(width 0.1524)
				(type default)
			)
			(layer "B.SilkS")
		)
		(fp_line
			(start 0.7874 0.4064)
			(end 0.7874 -0.4064)
			(stroke
				(width 0.1524)
				(type default)
			)
			(layer "B.SilkS")
		)
		(fp_line
			(start -0.7874 -0.4064)
			(end -0.7874 0.4064)
			(stroke
				(width 0.1524)
				(type default)
			)
			(layer "B.SilkS")
		)
		(fp_line
			(start 0.7874 -0.4064)
			(end -0.7874 -0.4064)
			(stroke
				(width 0.1524)
				(type default)
			)
			(layer "B.SilkS")
		)
		(fp_line
			(start -0.67945 0.3048)
			(end -0.120396 0.3048)
			(stroke
				(width 0.1)
				(type default)
			)
			(layer "B.Fab")
		)
		(fp_line
			(start -0.120396 0.3048)
			(end -0.120396 0.2794)
			(stroke
				(width 0.1)
				(type default)
			)
			(layer "B.Fab")
		)
		(fp_line
			(start 0.12065 0.3048)
			(end 0.67945 0.3048)
			(stroke
				(width 0.1)
				(type default)
			)
			(layer "B.Fab")
		)
		(fp_line
			(start 0.67945 0.3048)
			(end 0.67945 -0.305054)
			(stroke
				(width 0.1)
				(type default)
			)
			(layer "B.Fab")
		)
		(fp_line
			(start -0.120396 0.2794)
			(end 0.12065 0.2794)
			(stroke
				(width 0.1)
				(type default)
			)
			(layer "B.Fab")
		)
		(fp_line
			(start 0.12065 0.2794)
			(end 0.12065 0.3048)
			(stroke
				(width 0.1)
				(type default)
			)
			(layer "B.Fab")
		)
		(fp_line
			(start -0.12065 -0.2794)
			(end -0.12065 -0.3048)
			(stroke
				(width 0.1)
				(type default)
			)
			(layer "B.Fab")
		)
		(fp_line
			(start 0.12065 -0.2794)
			(end -0.12065 -0.2794)
			(stroke
				(width 0.1)
				(type default)
			)
			(layer "B.Fab")
		)
		(fp_line
			(start -0.67945 -0.3048)
			(end -0.67945 0.3048)
			(stroke
				(width 0.1)
				(type default)
			)
			(layer "B.Fab")
		)
		(fp_line
			(start -0.12065 -0.3048)
			(end -0.67945 -0.3048)
			(stroke
				(width 0.1)
				(type default)
			)
			(layer "B.Fab")
		)
		(fp_line
			(start 0.12065 -0.305054)
			(end 0.12065 -0.2794)
			(stroke
				(width 0.1)
				(type default)
			)
			(layer "B.Fab")
		)
		(fp_line
			(start 0.67945 -0.305054)
			(end 0.12065 -0.305054)
			(stroke
				(width 0.1)
				(type default)
			)
			(layer "B.Fab")
		)
		(pad "1" smd circle
			(at 0.40005 0 90)
			(size 0 0)
			(layers "B.Cu" "B.Mask" "B.Paste")
			(net "P12V_HSC_SENSE2_P")
		)
		(pad "2" smd circle
			(at -0.40005 0 90)
			(size 0 0)
			(layers "B.Cu" "B.Mask" "B.Paste")
			(net "P12V_HSC_SENSE2_R3_P")
		)
	)
	(footprint ""
		(layer "B.Cu")
		(at 100.306886 -359.788714 180)
		(property "Reference" "R2551"
			(at 0 0 0)
			(layer "B.SilkS")
			(hide yes)
			(effects
				(font
					(size 1.27 1.27)
				)
				(justify mirror)
			)
		)
		(property "Value" ""
			(at 0 0 0)
			(layer "B.Fab")
			(effects
				(font
					(size 1.27 1.27)
				)
				(justify mirror)
			)
		)
		(duplicate_pad_numbers_are_jumpers no)
		(fp_line
			(start 0.7874 0.4064)
			(end 0.7874 -0.4064)
			(stroke
				(width 0.1524)
				(type default)
			)
			(layer "B.SilkS")
		)
		(fp_line
			(start 0.7874 -0.4064)
			(end -0.7874 -0.4064)
			(stroke
				(width 0.1524)
				(type default)
			)
			(layer "B.SilkS")
		)
		(fp_line
			(start -0.7874 0.4064)
			(end 0.7874 0.4064)
			(stroke
				(width 0.1524)
				(type default)
			)
			(layer "B.SilkS")
		)
		(fp_line
			(start -0.7874 -0.4064)
			(end -0.7874 0.4064)
			(stroke
				(width 0.1524)
				(type default)
			)
			(layer "B.SilkS")
		)
		(fp_line
			(start 0.67945 0.3048)
			(end 0.67945 -0.305054)
			(stroke
				(width 0.1)
				(type default)
			)
			(layer "B.Fab")
		)
		(fp_line
			(start 0.67945 -0.305054)
			(end 0.12065 -0.305054)
			(stroke
				(width 0.1)
				(type default)
			)
			(layer "B.Fab")
		)
		(fp_line
			(start 0.12065 0.3048)
			(end 0.67945 0.3048)
			(stroke
				(width 0.1)
				(type default)
			)
			(layer "B.Fab")
		)
		(fp_line
			(start 0.12065 0.2794)
			(end 0.12065 0.3048)
			(stroke
				(width 0.1)
				(type default)
			)
			(layer "B.Fab")
		)
		(fp_line
			(start 0.12065 -0.2794)
			(end -0.12065 -0.2794)
			(stroke
				(width 0.1)
				(type default)
			)
			(layer "B.Fab")
		)
		(fp_line
			(start 0.12065 -0.305054)
			(end 0.12065 -0.2794)
			(stroke
				(width 0.1)
				(type default)
			)
			(layer "B.Fab")
		)
		(fp_line
			(start -0.120396 0.3048)
			(end -0.120396 0.2794)
			(stroke
				(width 0.1)
				(type default)
			)
			(layer "B.Fab")
		)
		(fp_line
			(start -0.120396 0.2794)
			(end 0.12065 0.2794)
			(stroke
				(width 0.1)
				(type default)
			)
			(layer "B.Fab")
		)
		(fp_line
			(start -0.12065 -0.2794)
			(end -0.12065 -0.3048)
			(stroke
				(width 0.1)
				(type default)
			)
			(layer "B.Fab")
		)
		(fp_line
			(start -0.12065 -0.3048)
			(end -0.67945 -0.3048)
			(stroke
				(width 0.1)
				(type default)
			)
			(layer "B.Fab")
		)
		(fp_line
			(start -0.67945 0.3048)
			(end -0.120396 0.3048)
			(stroke
				(width 0.1)
				(type default)
			)
			(layer "B.Fab")
		)
		(fp_line
			(start -0.67945 -0.3048)
			(end -0.67945 0.3048)
			(stroke
				(width 0.1)
				(type default)
			)
			(layer "B.Fab")
		)
		(pad "1" smd circle
			(at 0.40005 0)
			(size 0 0)
			(layers "B.Cu" "B.Mask" "B.Paste")
			(net "P3V3_AUX")
		)
		(pad "2" smd circle
			(at -0.40005 0)
			(size 0 0)
			(layers "B.Cu" "B.Mask" "B.Paste")
			(net "PWRGD_PVCCFA_EHV_FIVRA_CPU1_R")
		)
	)
)
